# TIMECARD (Time Appliance Project (Time Card)) — schematic netlist excerpt (pin names and nets, part order shuffled) for the footprints in the layout excerpt that follows; sources: Cadence DE-HDL packaged netlist, KiCad conversion of R4006-B0001-02_R01.brd

U8  LM75BDP_TSSOP8  pkg SOP8_118_P0256_V2  page 17
  SDA  = R_LM75B_1_I2C_SDA
  SCL  = LM75B_I2C_SCL
  OS  = FPGA_IN_LM75B_INT1_N
  GND  = SG
  A2  = UNNAMED_6_LM75BDPTSSOP8_I34_A2
  A1  = UNNAMED_6_LM75BDPTSSOP8_I34_A1
  A0  = UNNAMED_6_LM75BDPTSSOP8_I34_A0
  VCC  = XP3R3V_FPGA

(kicad_pcb
	(version 20260206)
	(generator "pcbnew")
	(generator_version "10.0")
	(general
		(thickness 1.6)
		(legacy_teardrops no)
	)
	(paper "A4")
	(title_block
		(title "timecard-production-celestica-r4006 — R4006-B0001-02_R01.brd")
		(comment 1 "Time Appliance Project (Time Card) / footprints 919-919 of 1113")
	)
	(layers
		(0 "F.Cu" signal "TOP")
		(4 "In1.Cu" signal "L02_GND1")
		(6 "In2.Cu" signal "L03_SIG1")
		(8 "In3.Cu" signal "L04_GND2")
		(10 "In4.Cu" signal "L05_VCC1")
		(12 "In5.Cu" signal "L06_VCC2")
		(14 "In6.Cu" signal "L07_GND3")
		(16 "In7.Cu" signal "L08_SIG2")
		(18 "In8.Cu" signal "L09_GND4")
		(2 "B.Cu" signal "BOTTOM")
		(9 "F.Adhes" user "F.Adhesive")
		(11 "B.Adhes" user "B.Adhesive")
		(13 "F.Paste" user "Package Geometry/Pastemask Top")
		(15 "B.Paste" user "Package Geometry/Pastemask Bottom")
		(5 "F.SilkS" user "Ref Des/Silkscreen Top")
		(7 "B.SilkS" user "Ref Des/Silkscreen Bottom")
		(1 "F.Mask" user "Board Geometry/Soldermask Top")
		(3 "B.Mask" user "Board Geometry/Soldermask Bottom")
		(17 "Dwgs.User" user "User.Drawings")
		(19 "Cmts.User" user "User.Comments")
		(21 "Eco1.User" user "User.Eco1")
		(23 "Eco2.User" user "User.Eco2")
		(25 "Edge.Cuts" user "Board Geometry/Outline")
		(27 "Margin" user)
		(31 "F.CrtYd" user "Package Geometry/Place Bound Top")
		(29 "B.CrtYd" user "Package Geometry/Place Bound Bottom")
		(35 "F.Fab" user "Ref Des/Assembly Top")
		(33 "B.Fab" user "Ref Des/Assembly Bottom")
	)
	(footprint ""
		(layer "B.Cu")
		(at 11.684 -75.946)
		(property "Reference" "U8"
			(at 1.27 2.83337 0)
			(unlocked yes)
			(layer "B.SilkS")
			(effects
				(font
					(size 0.7874 0.5842)
					(thickness 0.1524)
				)
				(justify mirror)
			)
		)
		(property "Value" ""
			(at 0 0 0)
			(layer "B.Fab")
			(effects
				(font
					(size 1.27 1.27)
				)
				(justify mirror)
			)
		)
		(property "Device Type" "LM75BDP_TSSOP8-G220-10215-01"
			(at 0.03175 2.55651 0)
			(unlocked yes)
			(layer "B.Fab")
			(hide yes)
			(effects
				(font
					(size 0.7874 0.5842)
					(thickness 0.1524)
				)
				(justify mirror)
			)
		)
		(property "User Part Number" "PARTNUM*"
			(at 0.037592 3.488182 0)
			(unlocked yes)
			(layer "Cmts.User")
			(hide yes)
			(effects
				(font
					(size 0.7874 0.5842)
					(thickness 0.1524)
				)
				(justify mirror)
			)
		)
		(duplicate_pad_numbers_are_jumpers no)
		(fp_line
			(start -3.3147 -1.45796)
			(end -1.778 -1.45796)
			(stroke
				(width 0.1)
				(type default)
			)
			(layer "B.SilkS")
		)
		(fp_line
			(start -3.3147 1.45796)
			(end -3.3147 -1.45796)
			(stroke
				(width 0.1)
				(type default)
			)
			(layer "B.SilkS")
		)
		(fp_line
			(start -1.778 -1.778)
			(end 1.778 -1.778)
			(stroke
				(width 0.1)
				(type default)
			)
			(layer "B.SilkS")
		)
		(fp_line
			(start -1.778 -1.45796)
			(end -1.778 -1.778)
			(stroke
				(width 0.1)
				(type default)
			)
			(layer "B.SilkS")
		)
		(fp_line
			(start -1.778 1.45796)
			(end -3.3147 1.45796)
			(stroke
				(width 0.1)
				(type default)
			)
			(layer "B.SilkS")
		)
		(fp_line
			(start -1.778 1.778)
			(end -1.778 1.45796)
			(stroke
				(width 0.1)
				(type default)
			)
			(layer "B.SilkS")
		)
		(fp_line
			(start 1.778 -1.778)
			(end 1.778 -1.45796)
			(stroke
				(width 0.1)
				(type default)
			)
			(layer "B.SilkS")
		)
		(fp_line
			(start 1.778 -1.45796)
			(end 3.3147 -1.45796)
			(stroke
				(width 0.1)
				(type default)
			)
			(layer "B.SilkS")
		)
		(fp_line
			(start 1.778 1.45796)
			(end 1.778 1.778)
			(stroke
				(width 0.1)
				(type default)
			)
			(layer "B.SilkS")
		)
		(fp_line
			(start 1.778 1.778)
			(end -1.778 1.778)
			(stroke
				(width 0.1)
				(type default)
			)
			(layer "B.SilkS")
		)
		(fp_line
			(start 3.3147 -1.45796)
			(end 3.3147 1.45796)
			(stroke
				(width 0.1)
				(type default)
			)
			(layer "B.SilkS")
		)
		(fp_line
			(start 3.3147 1.45796)
			(end 1.778 1.45796)
			(stroke
				(width 0.1)
				(type default)
			)
			(layer "B.SilkS")
		)
		(fp_poly
			(pts
				(arc
					(start 3.77952 -2.15392)
					(mid 3.01752 -2.15392)
					(end 3.77952 -2.15392)
				)
			)
			(stroke
				(width 0)
				(type default)
			)
			(fill yes)
			(layer "B.SilkS")
		)
		(fp_rect
			(start 3.5687 -2.032)
			(end -3.5687 2.032)
			(stroke
				(width 0)
				(type default)
			)
			(fill no)
			(layer "B.CrtYd")
		)
		(fp_line
			(start -1.524 -1.524)
			(end -1.524 1.524)
			(stroke
				(width 0.1)
				(type default)
			)
			(layer "B.Fab")
		)
		(fp_line
			(start -1.524 1.524)
			(end 1.524 1.524)
			(stroke
				(width 0.1)
				(type default)
			)
			(layer "B.Fab")
		)
		(fp_line
			(start 1.524 -1.524)
			(end -1.524 -1.524)
			(stroke
				(width 0.1)
				(type default)
			)
			(layer "B.Fab")
		)
		(fp_line
			(start 1.524 1.524)
			(end 1.524 -1.524)
			(stroke
				(width 0.1)
				(type default)
			)
			(layer "B.Fab")
		)
		(fp_poly
			(pts
				(arc
					(start 1.3716 -0.9398)
					(mid 0.6096 -0.9398)
					(end 1.3716 -0.9398)
				)
			)
			(stroke
				(width 0)
				(type default)
			)
			(fill yes)
			(layer "B.Fab")
		)
		(fp_text user "8"
			(at -3.81 -1.35763 0)
			(unlocked yes)
			(layer "B.SilkS")
			(effects
				(font
					(size 0.7874 0.5842)
					(thickness 0.1524)
				)
				(justify mirror)
			)
		)
		(fp_text user "5"
			(at -3.683 1.05537 0)
			(unlocked yes)
			(layer "B.SilkS")
			(effects
				(font
					(size 0.7874 0.5842)
					(thickness 0.1524)
				)
				(justify mirror)
			)
		)
		(fp_text user "4"
			(at 3.81 0.80137 0)
			(unlocked yes)
			(layer "B.SilkS")
			(effects
				(font
					(size 0.7874 0.5842)
					(thickness 0.1524)
				)
				(justify mirror)
			)
		)
		(fp_text user "8"
			(at -2.3368 -1.429258 0)
			(unlocked yes)
			(layer "B.Fab")
			(effects
				(font
					(size 0.7874 0.5842)
					(thickness 0.1524)
				)
				(justify mirror)
			)
		)
		(fp_text user "5"
			(at -2.0828 1.237742 0)
			(unlocked yes)
			(layer "B.Fab")
			(effects
				(font
					(size 0.7874 0.5842)
					(thickness 0.1524)
				)
				(justify mirror)
			)
		)
		(fp_text user "4"
			(at 2.1082 1.110742 0)
			(unlocked yes)
			(layer "B.Fab")
			(effects
				(font
					(size 0.7874 0.5842)
					(thickness 0.1524)
				)
				(justify mirror)
			)
		)
		(pad "1" smd rect
			(at 2.2987 -0.97536 90)
			(size 0.4572 1.524)
			(layers "B.Cu" "B.Mask" "B.Paste")
			(net "R_LM75B_1_I2C_SDA")
		)
		(pad "2" smd rect
			(at 2.2987 -0.32512 90)
			(size 0.4572 1.524)
			(layers "B.Cu" "B.Mask" "B.Paste")
			(net "LM75B_I2C_SCL")
		)
		(pad "3" smd rect
			(at 2.2987 0.32512 90)
			(size 0.4572 1.524)
			(layers "B.Cu" "B.Mask" "B.Paste")
			(net "FPGA_IN_LM75B_INT1_N")
		)
		(pad "4" smd rect
			(at 2.2987 0.97536 90)
			(size 0.4572 1.524)
			(layers "B.Cu" "B.Mask" "B.Paste")
			(net "SG")
		)
		(pad "5" smd rect
			(at -2.2987 0.97536 90)
			(size 0.4572 1.524)
			(layers "B.Cu" "B.Mask" "B.Paste")
			(net "UNNAMED_6_LM75BDPTSSOP8_I34_A2")
		)
		(pad "6" smd rect
			(at -2.2987 0.32512 90)
			(size 0.4572 1.524)
			(layers "B.Cu" "B.Mask" "B.Paste")
			(net "UNNAMED_6_LM75BDPTSSOP8_I34_A1")
		)
		(pad "7" smd rect
			(at -2.2987 -0.32512 90)
			(size 0.4572 1.524)
			(layers "B.Cu" "B.Mask" "B.Paste")
			(net "UNNAMED_6_LM75BDPTSSOP8_I34_A0")
		)
		(pad "8" smd rect
			(at -2.2987 -0.97536 90)
			(size 0.4572 1.524)
			(layers "B.Cu" "B.Mask" "B.Paste")
			(net "XP3R3V_FPGA")
		)
	)
)
